(kicad_pcb
	(version 20260206)
	(generator "pcbnew")
	(generator_version "10.0")
	(general
		(thickness 1.6)
		(legacy_teardrops no)
	)
	(paper "A4")
	(title_block
		(title "01162023_DA0F0TEBIF0_F0T_Expander_BD_F_brd_V02_OCP.brd")
		(comment 1 "Grand Teton / footprints 6186-6192 of 9728")
	)
	(layers
		(0 "F.Cu" signal "TOP")
		(4 "In1.Cu" signal "GND")
		(6 "In2.Cu" signal "VCC")
		(8 "In3.Cu" signal "VCC1")
		(10 "In4.Cu" signal "GND1")
		(12 "In5.Cu" signal "IN1")
		(14 "In6.Cu" signal "GND2")
		(16 "In7.Cu" signal "IN2")
		(18 "In8.Cu" signal "GND3")
		(20 "In9.Cu" signal "IN3")
		(22 "In10.Cu" signal "GND4")
		(24 "In11.Cu" signal "IN4")
		(26 "In12.Cu" signal "GND5")
		(28 "In13.Cu" signal "IN5")
		(30 "In14.Cu" signal "GND6")
		(32 "In15.Cu" signal "IN6")
		(34 "In16.Cu" signal "GND7")
		(2 "B.Cu" signal "BOTTOM")
		(9 "F.Adhes" user "F.Adhesive")
		(11 "B.Adhes" user "B.Adhesive")
		(13 "F.Paste" user "Package Geometry/Pastemask Top")
		(15 "B.Paste" user "Package Geometry/Pastemask Bottom")
		(5 "F.SilkS" user "Ref Des/Silkscreen Top")
		(7 "B.SilkS" user "Ref Des/Silkscreen Bottom")
		(1 "F.Mask" user "Board Geometry/Soldermask Top")
		(3 "B.Mask" user "Board Geometry/Soldermask Bottom")
		(17 "Dwgs.User" user "User.Drawings")
		(19 "Cmts.User" user "User.Comments")
		(21 "Eco1.User" user "User.Eco1")
		(23 "Eco2.User" user "User.Eco2")
		(25 "Edge.Cuts" user "Board Geometry/Outline")
		(27 "Margin" user)
		(31 "F.CrtYd" user "Package Geometry/Place Bound Top")
		(29 "B.CrtYd" user "Package Geometry/Place Bound Bottom")
		(35 "F.Fab" user "Ref Des/Assembly Top")
		(33 "B.Fab" user "Ref Des/Assembly Bottom")
	)
	(footprint ""
		(layer "F.Cu")
		(at 460.611982 -108.737654 180)
		(property "Reference" "C982"
			(at 0 0 180)
			(layer "F.SilkS")
			(hide yes)
			(effects
				(font
					(size 1.27 1.27)
				)
			)
		)
		(property "Value" ""
			(at 0 0 180)
			(layer "F.Fab")
			(effects
				(font
					(size 1.27 1.27)
				)
			)
		)
		(duplicate_pad_numbers_are_jumpers no)
		(fp_line
			(start 0.7874 0.4064)
			(end -0.7874 0.4064)
			(stroke
				(width 0.1524)
				(type default)
			)
			(layer "F.SilkS")
		)
		(fp_line
			(start 0.7874 -0.4064)
			(end 0.7874 0.4064)
			(stroke
				(width 0.1524)
				(type default)
			)
			(layer "F.SilkS")
		)
		(fp_line
			(start -0.7874 0.4064)
			(end -0.7874 -0.4064)
			(stroke
				(width 0.1524)
				(type default)
			)
			(layer "F.SilkS")
		)
		(fp_line
			(start -0.7874 -0.4064)
			(end 0.7874 -0.4064)
			(stroke
				(width 0.1524)
				(type default)
			)
			(layer "F.SilkS")
		)
		(fp_line
			(start 0.67945 0.3048)
			(end 0.120396 0.3048)
			(stroke
				(width 0.1)
				(type default)
			)
			(layer "F.Fab")
		)
		(fp_line
			(start 0.67945 -0.3048)
			(end 0.67945 0.3048)
			(stroke
				(width 0.1)
				(type default)
			)
			(layer "F.Fab")
		)
		(fp_line
			(start 0.12065 -0.2794)
			(end 0.12065 -0.3048)
			(stroke
				(width 0.1)
				(type default)
			)
			(layer "F.Fab")
		)
		(fp_line
			(start 0.12065 -0.3048)
			(end 0.67945 -0.3048)
			(stroke
				(width 0.1)
				(type default)
			)
			(layer "F.Fab")
		)
		(fp_line
			(start 0.120396 0.3048)
			(end 0.120396 0.2794)
			(stroke
				(width 0.1)
				(type default)
			)
			(layer "F.Fab")
		)
		(fp_line
			(start 0.120396 0.2794)
			(end -0.12065 0.2794)
			(stroke
				(width 0.1)
				(type default)
			)
			(layer "F.Fab")
		)
		(fp_line
			(start -0.12065 0.3048)
			(end -0.67945 0.3048)
			(stroke
				(width 0.1)
				(type default)
			)
			(layer "F.Fab")
		)
		(fp_line
			(start -0.12065 0.2794)
			(end -0.12065 0.3048)
			(stroke
				(width 0.1)
				(type default)
			)
			(layer "F.Fab")
		)
		(fp_line
			(start -0.12065 -0.2794)
			(end 0.12065 -0.2794)
			(stroke
				(width 0.1)
				(type default)
			)
			(layer "F.Fab")
		)
		(fp_line
			(start -0.12065 -0.305054)
			(end -0.12065 -0.2794)
			(stroke
				(width 0.1)
				(type default)
			)
			(layer "F.Fab")
		)
		(fp_line
			(start -0.67945 0.3048)
			(end -0.67945 -0.305054)
			(stroke
				(width 0.1)
				(type default)
			)
			(layer "F.Fab")
		)
		(fp_line
			(start -0.67945 -0.305054)
			(end -0.12065 -0.305054)
			(stroke
				(width 0.1)
				(type default)
			)
			(layer "F.Fab")
		)
		(pad "1" smd circle
			(at -0.40005 0 180)
			(size 0 0)
			(layers "F.Cu" "F.Mask" "F.Paste")
			(net "GND")
		)
		(pad "2" smd circle
			(at 0.40005 0 180)
			(size 0 0)
			(layers "F.Cu" "F.Mask" "F.Paste")
			(net "P12V_NIC7_CO_EN")
		)
	)
	(footprint ""
		(layer "F.Cu")
		(at 13.953744 -115.147852 -90)
		(property "Reference" "PC658"
			(at 0 0 270)
			(layer "F.SilkS")
			(hide yes)
			(effects
				(font
					(size 1.27 1.27)
				)
			)
		)
		(property "Value" ""
			(at 0 0 270)
			(layer "F.Fab")
			(effects
				(font
					(size 1.27 1.27)
				)
			)
		)
		(duplicate_pad_numbers_are_jumpers no)
		(fp_line
			(start -0.7874 0.4064)
			(end -0.7874 -0.4064)
			(stroke
				(width 0.1524)
				(type default)
			)
			(layer "F.SilkS")
		)
		(fp_line
			(start 0.7874 0.4064)
			(end -0.7874 0.4064)
			(stroke
				(width 0.1524)
				(type default)
			)
			(layer "F.SilkS")
		)
		(fp_line
			(start -0.7874 -0.4064)
			(end 0.7874 -0.4064)
			(stroke
				(width 0.1524)
				(type default)
			)
			(layer "F.SilkS")
		)
		(fp_line
			(start 0.7874 -0.4064)
			(end 0.7874 0.4064)
			(stroke
				(width 0.1524)
				(type default)
			)
			(layer "F.SilkS")
		)
		(fp_line
			(start -0.67945 0.3048)
			(end -0.67945 -0.305054)
			(stroke
				(width 0.1)
				(type default)
			)
			(layer "F.Fab")
		)
		(fp_line
			(start -0.12065 0.3048)
			(end -0.67945 0.3048)
			(stroke
				(width 0.1)
				(type default)
			)
			(layer "F.Fab")
		)
		(fp_line
			(start 0.120396 0.3048)
			(end 0.120396 0.2794)
			(stroke
				(width 0.1)
				(type default)
			)
			(layer "F.Fab")
		)
		(fp_line
			(start 0.67945 0.3048)
			(end 0.120396 0.3048)
			(stroke
				(width 0.1)
				(type default)
			)
			(layer "F.Fab")
		)
		(fp_line
			(start -0.12065 0.2794)
			(end -0.12065 0.3048)
			(stroke
				(width 0.1)
				(type default)
			)
			(layer "F.Fab")
		)
		(fp_line
			(start 0.120396 0.2794)
			(end -0.12065 0.2794)
			(stroke
				(width 0.1)
				(type default)
			)
			(layer "F.Fab")
		)
		(fp_line
			(start -0.12065 -0.2794)
			(end 0.12065 -0.2794)
			(stroke
				(width 0.1)
				(type default)
			)
			(layer "F.Fab")
		)
		(fp_line
			(start 0.12065 -0.2794)
			(end 0.12065 -0.3048)
			(stroke
				(width 0.1)
				(type default)
			)
			(layer "F.Fab")
		)
		(fp_line
			(start 0.12065 -0.3048)
			(end 0.67945 -0.3048)
			(stroke
				(width 0.1)
				(type default)
			)
			(layer "F.Fab")
		)
		(fp_line
			(start 0.67945 -0.3048)
			(end 0.67945 0.3048)
			(stroke
				(width 0.1)
				(type default)
			)
			(layer "F.Fab")
		)
		(fp_line
			(start -0.67945 -0.305054)
			(end -0.12065 -0.305054)
			(stroke
				(width 0.1)
				(type default)
			)
			(layer "F.Fab")
		)
		(fp_line
			(start -0.12065 -0.305054)
			(end -0.12065 -0.2794)
			(stroke
				(width 0.1)
				(type default)
			)
			(layer "F.Fab")
		)
		(pad "1" smd circle
			(at -0.40005 0 270)
			(size 0 0)
			(layers "F.Cu" "F.Mask" "F.Paste")
			(net "P3V3_AUX")
		)
		(pad "2" smd circle
			(at 0.40005 0 270)
			(size 0 0)
			(layers "F.Cu" "F.Mask" "F.Paste")
			(net "GND")
		)
	)
	(footprint ""
		(layer "F.Cu")
		(at 124.991114 -252.416564 90)
		(property "Reference" "R828"
			(at 0 0 90)
			(layer "F.SilkS")
			(hide yes)
			(effects
				(font
					(size 1.27 1.27)
				)
			)
		)
		(property "Value" ""
			(at 0 0 90)
			(layer "F.Fab")
			(effects
				(font
					(size 1.27 1.27)
				)
			)
		)
		(duplicate_pad_numbers_are_jumpers no)
		(fp_line
			(start 0.7874 -0.4064)
			(end 0.7874 0.4064)
			(stroke
				(width 0.1524)
				(type default)
			)
			(layer "F.SilkS")
		)
		(fp_line
			(start -0.7874 -0.4064)
			(end 0.7874 -0.4064)
			(stroke
				(width 0.1524)
				(type default)
			)
			(layer "F.SilkS")
		)
		(fp_line
			(start 0.7874 0.4064)
			(end -0.7874 0.4064)
			(stroke
				(width 0.1524)
				(type default)
			)
			(layer "F.SilkS")
		)
		(fp_line
			(start -0.7874 0.4064)
			(end -0.7874 -0.4064)
			(stroke
				(width 0.1524)
				(type default)
			)
			(layer "F.SilkS")
		)
		(fp_line
			(start -0.12065 -0.305054)
			(end -0.12065 -0.2794)
			(stroke
				(width 0.1)
				(type default)
			)
			(layer "F.Fab")
		)
		(fp_line
			(start -0.67945 -0.305054)
			(end -0.12065 -0.305054)
			(stroke
				(width 0.1)
				(type default)
			)
			(layer "F.Fab")
		)
		(fp_line
			(start 0.67945 -0.3048)
			(end 0.67945 0.3048)
			(stroke
				(width 0.1)
				(type default)
			)
			(layer "F.Fab")
		)
		(fp_line
			(start 0.12065 -0.3048)
			(end 0.67945 -0.3048)
			(stroke
				(width 0.1)
				(type default)
			)
			(layer "F.Fab")
		)
		(fp_line
			(start 0.12065 -0.2794)
			(end 0.12065 -0.3048)
			(stroke
				(width 0.1)
				(type default)
			)
			(layer "F.Fab")
		)
		(fp_line
			(start -0.12065 -0.2794)
			(end 0.12065 -0.2794)
			(stroke
				(width 0.1)
				(type default)
			)
			(layer "F.Fab")
		)
		(fp_line
			(start 0.120396 0.2794)
			(end -0.12065 0.2794)
			(stroke
				(width 0.1)
				(type default)
			)
			(layer "F.Fab")
		)
		(fp_line
			(start -0.12065 0.2794)
			(end -0.12065 0.3048)
			(stroke
				(width 0.1)
				(type default)
			)
			(layer "F.Fab")
		)
		(fp_line
			(start 0.67945 0.3048)
			(end 0.120396 0.3048)
			(stroke
				(width 0.1)
				(type default)
			)
			(layer "F.Fab")
		)
		(fp_line
			(start 0.120396 0.3048)
			(end 0.120396 0.2794)
			(stroke
				(width 0.1)
				(type default)
			)
			(layer "F.Fab")
		)
		(fp_line
			(start -0.12065 0.3048)
			(end -0.67945 0.3048)
			(stroke
				(width 0.1)
				(type default)
			)
			(layer "F.Fab")
		)
		(fp_line
			(start -0.67945 0.3048)
			(end -0.67945 -0.305054)
			(stroke
				(width 0.1)
				(type default)
			)
			(layer "F.Fab")
		)
		(pad "1" smd circle
			(at -0.40005 0 90)
			(size 0 0)
			(layers "F.Cu" "F.Mask" "F.Paste")
			(net "SMB_BIC_I2C6_MUX_VR_R_SCL")
		)
		(pad "2" smd circle
			(at 0.40005 0 90)
			(size 0 0)
			(layers "F.Cu" "F.Mask" "F.Paste")
			(net "SMB_VR_P0V8_PEX0_SCL")
		)
	)
	(footprint ""
		(layer "F.Cu")
		(at 227.581206 -254.18542 -90)
		(property "Reference" "C4298"
			(at 0 0 270)
			(layer "F.SilkS")
			(hide yes)
			(effects
				(font
					(size 1.27 1.27)
				)
			)
		)
		(property "Value" ""
			(at 0 0 270)
			(layer "F.Fab")
			(effects
				(font
					(size 1.27 1.27)
				)
			)
		)
		(duplicate_pad_numbers_are_jumpers no)
		(fp_line
			(start -1.2954 0.5842)
			(end -1.2954 -0.5842)
			(stroke
				(width 0.1524)
				(type default)
			)
			(layer "F.SilkS")
		)
		(fp_line
			(start 1.2954 0.5842)
			(end -1.2954 0.5842)
			(stroke
				(width 0.1524)
				(type default)
			)
			(layer "F.SilkS")
		)
		(fp_line
			(start -1.2954 -0.5842)
			(end 1.2954 -0.5842)
			(stroke
				(width 0.1524)
				(type default)
			)
			(layer "F.SilkS")
		)
		(fp_line
			(start 1.2954 -0.5842)
			(end 1.2954 0.5842)
			(stroke
				(width 0.1524)
				(type default)
			)
			(layer "F.SilkS")
		)
		(fp_line
			(start -0.8636 0.4572)
			(end -0.8636 0.4064)
			(stroke
				(width 0.1)
				(type default)
			)
			(layer "F.Fab")
		)
		(fp_line
			(start 0.8636 0.4572)
			(end -0.8636 0.4572)
			(stroke
				(width 0.1)
				(type default)
			)
			(layer "F.Fab")
		)
		(fp_line
			(start -1.1938 0.4064)
			(end -1.1938 -0.4064)
			(stroke
				(width 0.1)
				(type default)
			)
			(layer "F.Fab")
		)
		(fp_line
			(start -0.8636 0.4064)
			(end -1.1938 0.4064)
			(stroke
				(width 0.1)
				(type default)
			)
			(layer "F.Fab")
		)
		(fp_line
			(start 0.8636 0.4064)
			(end 0.8636 0.4572)
			(stroke
				(width 0.1)
				(type default)
			)
			(layer "F.Fab")
		)
		(fp_line
			(start 1.1938 0.4064)
			(end 0.8636 0.4064)
			(stroke
				(width 0.1)
				(type default)
			)
			(layer "F.Fab")
		)
		(fp_line
			(start -1.1938 -0.4064)
			(end -0.8636 -0.4064)
			(stroke
				(width 0.1)
				(type default)
			)
			(layer "F.Fab")
		)
		(fp_line
			(start -0.8636 -0.4064)
			(end -0.8636 -0.4572)
			(stroke
				(width 0.1)
				(type default)
			)
			(layer "F.Fab")
		)
		(fp_line
			(start 0.8636 -0.4064)
			(end 1.1938 -0.4064)
			(stroke
				(width 0.1)
				(type default)
			)
			(layer "F.Fab")
		)
		(fp_line
			(start 1.1938 -0.4064)
			(end 1.1938 0.4064)
			(stroke
				(width 0.1)
				(type default)
			)
			(layer "F.Fab")
		)
		(fp_line
			(start -0.8636 -0.4572)
			(end 0.8636 -0.4572)
			(stroke
				(width 0.1)
				(type default)
			)
			(layer "F.Fab")
		)
		(fp_line
			(start 0.8636 -0.4572)
			(end 0.8636 -0.4064)
			(stroke
				(width 0.1)
				(type default)
			)
			(layer "F.Fab")
		)
		(pad "1" smd rect
			(at -0.7366 0 180)
			(size 0.7112 0.8128)
			(layers "F.Cu" "F.Mask" "F.Paste")
			(net "P1V25_SERDES_VDDPLL_PEX1_C8")
		)
		(pad "2" smd rect
			(at 0.7366 0 180)
			(size 0.7112 0.8128)
			(layers "F.Cu" "F.Mask" "F.Paste")
			(net "GND")
		)
	)
	(footprint ""
		(layer "F.Cu")
		(at 393.669266 -89.500202)
		(property "Reference" "R1761"
			(at 0 0 0)
			(layer "F.SilkS")
			(hide yes)
			(effects
				(font
					(size 1.27 1.27)
				)
			)
		)
		(property "Value" ""
			(at 0 0 0)
			(layer "F.Fab")
			(effects
				(font
					(size 1.27 1.27)
				)
			)
		)
		(duplicate_pad_numbers_are_jumpers no)
		(fp_line
			(start -0.7874 -0.4064)
			(end 0.7874 -0.4064)
			(stroke
				(width 0.1524)
				(type default)
			)
			(layer "F.SilkS")
		)
		(fp_line
			(start -0.7874 0.4064)
			(end -0.7874 -0.4064)
			(stroke
				(width 0.1524)
				(type default)
			)
			(layer "F.SilkS")
		)
		(fp_line
			(start 0.7874 -0.4064)
			(end 0.7874 0.4064)
			(stroke
				(width 0.1524)
				(type default)
			)
			(layer "F.SilkS")
		)
		(fp_line
			(start 0.7874 0.4064)
			(end -0.7874 0.4064)
			(stroke
				(width 0.1524)
				(type default)
			)
			(layer "F.SilkS")
		)
		(fp_line
			(start -0.67945 -0.305054)
			(end -0.12065 -0.305054)
			(stroke
				(width 0.1)
				(type default)
			)
			(layer "F.Fab")
		)
		(fp_line
			(start -0.67945 0.3048)
			(end -0.67945 -0.305054)
			(stroke
				(width 0.1)
				(type default)
			)
			(layer "F.Fab")
		)
		(fp_line
			(start -0.12065 -0.305054)
			(end -0.12065 -0.2794)
			(stroke
				(width 0.1)
				(type default)
			)
			(layer "F.Fab")
		)
		(fp_line
			(start -0.12065 -0.2794)
			(end 0.12065 -0.2794)
			(stroke
				(width 0.1)
				(type default)
			)
			(layer "F.Fab")
		)
		(fp_line
			(start -0.12065 0.2794)
			(end -0.12065 0.3048)
			(stroke
				(width 0.1)
				(type default)
			)
			(layer "F.Fab")
		)
		(fp_line
			(start -0.12065 0.3048)
			(end -0.67945 0.3048)
			(stroke
				(width 0.1)
				(type default)
			)
			(layer "F.Fab")
		)
		(fp_line
			(start 0.120396 0.2794)
			(end -0.12065 0.2794)
			(stroke
				(width 0.1)
				(type default)
			)
			(layer "F.Fab")
		)
		(fp_line
			(start 0.120396 0.3048)
			(end 0.120396 0.2794)
			(stroke
				(width 0.1)
				(type default)
			)
			(layer "F.Fab")
		)
		(fp_line
			(start 0.12065 -0.3048)
			(end 0.67945 -0.3048)
			(stroke
				(width 0.1)
				(type default)
			)
			(layer "F.Fab")
		)
		(fp_line
			(start 0.12065 -0.2794)
			(end 0.12065 -0.3048)
			(stroke
				(width 0.1)
				(type default)
			)
			(layer "F.Fab")
		)
		(fp_line
			(start 0.67945 -0.3048)
			(end 0.67945 0.3048)
			(stroke
				(width 0.1)
				(type default)
			)
			(layer "F.Fab")
		)
		(fp_line
			(start 0.67945 0.3048)
			(end 0.120396 0.3048)
			(stroke
				(width 0.1)
				(type default)
			)
			(layer "F.Fab")
		)
		(pad "1" smd circle
			(at -0.40005 0)
			(size 0 0)
			(layers "F.Cu" "F.Mask" "F.Paste")
			(net "BIC_I2C6_MUX_A2")
		)
		(pad "2" smd circle
			(at 0.40005 0)
			(size 0 0)
			(layers "F.Cu" "F.Mask" "F.Paste")
			(net "GND")
		)
	)
	(footprint ""
		(layer "F.Cu")
		(at 354.130864 -280.44902 -90)
		(property "Reference" "PR157"
			(at 0 0 270)
			(layer "F.SilkS")
			(hide yes)
			(effects
				(font
					(size 1.27 1.27)
				)
			)
		)
		(property "Value" ""
			(at 0 0 270)
			(layer "F.Fab")
			(effects
				(font
					(size 1.27 1.27)
				)
			)
		)
		(duplicate_pad_numbers_are_jumpers no)
		(fp_line
			(start -0.7874 0.4064)
			(end -0.7874 -0.4064)
			(stroke
				(width 0.1524)
				(type default)
			)
			(layer "F.SilkS")
		)
		(fp_line
			(start 0.7874 0.4064)
			(end -0.7874 0.4064)
			(stroke
				(width 0.1524)
				(type default)
			)
			(layer "F.SilkS")
		)
		(fp_line
			(start -0.7874 -0.4064)
			(end 0.7874 -0.4064)
			(stroke
				(width 0.1524)
				(type default)
			)
			(layer "F.SilkS")
		)
		(fp_line
			(start 0.7874 -0.4064)
			(end 0.7874 0.4064)
			(stroke
				(width 0.1524)
				(type default)
			)
			(layer "F.SilkS")
		)
		(fp_line
			(start -0.67945 0.3048)
			(end -0.67945 -0.305054)
			(stroke
				(width 0.1)
				(type default)
			)
			(layer "F.Fab")
		)
		(fp_line
			(start -0.12065 0.3048)
			(end -0.67945 0.3048)
			(stroke
				(width 0.1)
				(type default)
			)
			(layer "F.Fab")
		)
		(fp_line
			(start 0.120396 0.3048)
			(end 0.120396 0.2794)
			(stroke
				(width 0.1)
				(type default)
			)
			(layer "F.Fab")
		)
		(fp_line
			(start 0.67945 0.3048)
			(end 0.120396 0.3048)
			(stroke
				(width 0.1)
				(type default)
			)
			(layer "F.Fab")
		)
		(fp_line
			(start -0.12065 0.2794)
			(end -0.12065 0.3048)
			(stroke
				(width 0.1)
				(type default)
			)
			(layer "F.Fab")
		)
		(fp_line
			(start 0.120396 0.2794)
			(end -0.12065 0.2794)
			(stroke
				(width 0.1)
				(type default)
			)
			(layer "F.Fab")
		)
		(fp_line
			(start -0.12065 -0.2794)
			(end 0.12065 -0.2794)
			(stroke
				(width 0.1)
				(type default)
			)
			(layer "F.Fab")
		)
		(fp_line
			(start 0.12065 -0.2794)
			(end 0.12065 -0.3048)
			(stroke
				(width 0.1)
				(type default)
			)
			(layer "F.Fab")
		)
		(fp_line
			(start 0.12065 -0.3048)
			(end 0.67945 -0.3048)
			(stroke
				(width 0.1)
				(type default)
			)
			(layer "F.Fab")
		)
		(fp_line
			(start 0.67945 -0.3048)
			(end 0.67945 0.3048)
			(stroke
				(width 0.1)
				(type default)
			)
			(layer "F.Fab")
		)
		(fp_line
			(start -0.67945 -0.305054)
			(end -0.12065 -0.305054)
			(stroke
				(width 0.1)
				(type default)
			)
			(layer "F.Fab")
		)
		(fp_line
			(start -0.12065 -0.305054)
			(end -0.12065 -0.2794)
			(stroke
				(width 0.1)
				(type default)
			)
			(layer "F.Fab")
		)
		(pad "1" smd circle
			(at -0.40005 0 270)
			(size 0 0)
			(layers "F.Cu" "F.Mask" "F.Paste")
			(net "SW_P0V8_PEX3_BOOT1")
		)
		(pad "2" smd circle
			(at 0.40005 0 270)
			(size 0 0)
			(layers "F.Cu" "F.Mask" "F.Paste")
			(net "SW_P0V8_PEX3_BOOT1_R")
		)
	)
	(footprint ""
		(layer "F.Cu")
		(at 89.327482 -356.244906 90)
		(property "Reference" "C99"
			(at 0 0 90)
			(layer "F.SilkS")
			(hide yes)
			(effects
				(font
					(size 1.27 1.27)
				)
			)
		)
		(property "Value" ""
			(at 0 0 90)
			(layer "F.Fab")
			(effects
				(font
					(size 1.27 1.27)
				)
			)
		)
		(duplicate_pad_numbers_are_jumpers no)
		(fp_line
			(start 0.299974 -0.150114)
			(end 0.299974 0.150114)
			(stroke
				(width 0.1)
				(type default)
			)
			(layer "F.Fab")
		)
		(fp_line
			(start -0.299974 -0.150114)
			(end 0.299974 -0.150114)
			(stroke
				(width 0.1)
				(type default)
			)
			(layer "F.Fab")
		)
		(fp_line
			(start 0.299974 0.150114)
			(end -0.299974 0.150114)
			(stroke
				(width 0.1)
				(type default)
			)
			(layer "F.Fab")
		)
		(fp_line
			(start -0.299974 0.150114)
			(end -0.299974 -0.150114)
			(stroke
				(width 0.1)
				(type default)
			)
			(layer "F.Fab")
		)
		(pad "1" smd rect
			(at -0.2667 0 90)
			(size 0.3048 0.381)
			(layers "F.Cu" "F.Mask" "F.Paste")
			(net "P5E_PEX0_STN5_TX_DP<94>")
		)
		(pad "2" smd rect
			(at 0.2667 0 90)
			(size 0.3048 0.381)
			(layers "F.Cu" "F.Mask" "F.Paste")
			(net "P5E_PEX0_STN5_TX_C_DP<94>")
		)
	)
)
